(kicad_pcb
	(version 20260206)
	(generator "pcbnew")
	(generator_version "10.0")
	(general
		(thickness 1.6)
		(legacy_teardrops no)
	)
	(paper "A4")
	(title_block
		(title "01162023_DA0F0TEBIF0_F0T_Expander_BD_F_brd_V02_OCP.brd")
		(comment 1 "Grand Teton / footprints 4431-4436 of 9728")
	)
	(layers
		(0 "F.Cu" signal "TOP")
		(4 "In1.Cu" signal "GND")
		(6 "In2.Cu" signal "VCC")
		(8 "In3.Cu" signal "VCC1")
		(10 "In4.Cu" signal "GND1")
		(12 "In5.Cu" signal "IN1")
		(14 "In6.Cu" signal "GND2")
		(16 "In7.Cu" signal "IN2")
		(18 "In8.Cu" signal "GND3")
		(20 "In9.Cu" signal "IN3")
		(22 "In10.Cu" signal "GND4")
		(24 "In11.Cu" signal "IN4")
		(26 "In12.Cu" signal "GND5")
		(28 "In13.Cu" signal "IN5")
		(30 "In14.Cu" signal "GND6")
		(32 "In15.Cu" signal "IN6")
		(34 "In16.Cu" signal "GND7")
		(2 "B.Cu" signal "BOTTOM")
		(9 "F.Adhes" user "F.Adhesive")
		(11 "B.Adhes" user "B.Adhesive")
		(13 "F.Paste" user "Package Geometry/Pastemask Top")
		(15 "B.Paste" user "Package Geometry/Pastemask Bottom")
		(5 "F.SilkS" user "Ref Des/Silkscreen Top")
		(7 "B.SilkS" user "Ref Des/Silkscreen Bottom")
		(1 "F.Mask" user "Board Geometry/Soldermask Top")
		(3 "B.Mask" user "Board Geometry/Soldermask Bottom")
		(17 "Dwgs.User" user "User.Drawings")
		(19 "Cmts.User" user "User.Comments")
		(21 "Eco1.User" user "User.Eco1")
		(23 "Eco2.User" user "User.Eco2")
		(25 "Edge.Cuts" user "Board Geometry/Outline")
		(27 "Margin" user)
		(31 "F.CrtYd" user "Package Geometry/Place Bound Top")
		(29 "B.CrtYd" user "Package Geometry/Place Bound Bottom")
		(35 "F.Fab" user "Ref Des/Assembly Top")
		(33 "B.Fab" user "Ref Des/Assembly Bottom")
	)
	(footprint ""
		(layer "F.Cu")
		(at 160.041082 -438.984644 180)
		(property "Reference" "X66"
			(at -0.1778 -1.92913 180)
			(unlocked yes)
			(layer "F.SilkS")
			(effects
				(font
					(size 0.7874 0.5842)
					(thickness 0.1524)
				)
				(justify left)
			)
		)
		(property "Value" ""
			(at 0 0 180)
			(layer "F.Fab")
			(effects
				(font
					(size 1.27 1.27)
				)
			)
		)
		(property "Device Type" "TP_TDR_4P_FTS_MPKT4_H025P0200_IO_TP15_TP_TDR_4P_DIP"
			(at 1.30175 1.27 270)
			(unlocked yes)
			(layer "F.Fab")
			(hide yes)
			(effects
				(font
					(size 0.635 0.4064)
					(thickness 0.1524)
				)
			)
		)
		(property "User Part Number" "TP15"
			(at 1.30175 1.27 270)
			(unlocked yes)
			(layer "Cmts.User")
			(hide yes)
			(effects
				(font
					(size 0.635 0.4064)
					(thickness 0.1524)
				)
			)
		)
		(duplicate_pad_numbers_are_jumpers no)
		(fp_line
			(start 2.54 3.81)
			(end 2.54 3.6703)
			(stroke
				(width 0.1524)
				(type default)
			)
			(layer "F.SilkS")
		)
		(fp_line
			(start 2.54 1.4097)
			(end 2.54 1.1303)
			(stroke
				(width 0.1524)
				(type default)
			)
			(layer "F.SilkS")
		)
		(fp_line
			(start 2.54 -1.1303)
			(end 2.54 -1.27)
			(stroke
				(width 0.1524)
				(type default)
			)
			(layer "F.SilkS")
		)
		(fp_line
			(start 2.54 -1.27)
			(end 0 -1.27)
			(stroke
				(width 0.1524)
				(type default)
			)
			(layer "F.SilkS")
		)
		(fp_line
			(start 0 3.81)
			(end 2.54 3.81)
			(stroke
				(width 0.1524)
				(type default)
			)
			(layer "F.SilkS")
		)
		(fp_line
			(start 0 3.175)
			(end 0 3.81)
			(stroke
				(width 0.1524)
				(type default)
			)
			(layer "F.SilkS")
		)
		(fp_line
			(start 0 0.635)
			(end 0 1.905)
			(stroke
				(width 0.1524)
				(type default)
			)
			(layer "F.SilkS")
		)
		(fp_line
			(start 0 -1.27)
			(end 0 -0.635)
			(stroke
				(width 0.1524)
				(type default)
			)
			(layer "F.SilkS")
		)
		(fp_poly
			(pts
				(xy -0.761746 0) (xy -2.285746 -0.762) (xy -2.285746 0.762)
			)
			(stroke
				(width 0)
				(type default)
			)
			(fill yes)
			(layer "F.SilkS")
		)
		(fp_line
			(start 2.54 3.81)
			(end 2.54 -1.27)
			(stroke
				(width 0.1)
				(type default)
			)
			(layer "F.Fab")
		)
		(fp_line
			(start 2.54 -1.27)
			(end 0 -1.27)
			(stroke
				(width 0.1)
				(type default)
			)
			(layer "F.Fab")
		)
		(fp_line
			(start 0 3.81)
			(end 2.54 3.81)
			(stroke
				(width 0.1)
				(type default)
			)
			(layer "F.Fab")
		)
		(fp_line
			(start 0 -1.27)
			(end 0 3.81)
			(stroke
				(width 0.1)
				(type default)
			)
			(layer "F.Fab")
		)
		(fp_poly
			(pts
				(xy -0.761746 0) (xy -2.285746 -0.762) (xy -2.285746 0.762)
			)
			(stroke
				(width 0)
				(type default)
			)
			(fill yes)
			(layer "F.Fab")
		)
		(pad "1" thru_hole circle
			(at 0 0 180)
			(size 1.0033 1.0033)
			(drill 0.249936)
			(layers "*.Cu" "*.Mask")
			(remove_unused_layers no)
			(net "TDR_DIFF_100_TOP_DIP")
			(clearance 0.10795)
			(thermal_gap 0.10795)
			(padstack
				(mode front_inner_back)
				(layer "Inner"
					(shape circle)
					(size 0.8001 0.8001)
					(clearance 0.1524)
				)
				(layer "B.Cu"
					(shape circle)
					(size 1.0033 1.0033)
					(clearance 0.10795)
				)
			)
		)
		(pad "2" thru_hole circle
			(at 2.54 0 180)
			(size 1.9939 1.9939)
			(drill 0.249936)
			(layers "*.Cu" "*.Mask")
			(remove_unused_layers no)
			(net "COUPON_GND1")
			(clearance 0.10795)
			(thermal_gap 0.10795)
			(padstack
				(mode front_inner_back)
				(layer "Inner"
					(shape circle)
					(size 0.8001 0.8001)
					(clearance 0.1524)
				)
				(layer "B.Cu"
					(shape circle)
					(size 1.9939 1.9939)
					(clearance 0.10795)
				)
			)
		)
		(pad "3" thru_hole circle
			(at 2.54 2.54 180)
			(size 1.9939 1.9939)
			(drill 0.249936)
			(layers "*.Cu" "*.Mask")
			(remove_unused_layers no)
			(net "COUPON_GND1")
			(clearance 0.10795)
			(thermal_gap 0.10795)
			(padstack
				(mode front_inner_back)
				(layer "Inner"
					(shape circle)
					(size 0.8001 0.8001)
					(clearance 0.1524)
				)
				(layer "B.Cu"
					(shape circle)
					(size 1.9939 1.9939)
					(clearance 0.10795)
				)
			)
		)
		(pad "4" thru_hole circle
			(at 0 2.54 180)
			(size 1.0033 1.0033)
			(drill 0.249936)
			(layers "*.Cu" "*.Mask")
			(remove_unused_layers no)
			(net "TDR_DIFF_100_TOP_DIN")
			(clearance 0.10795)
			(thermal_gap 0.10795)
			(padstack
				(mode front_inner_back)
				(layer "Inner"
					(shape circle)
					(size 0.8001 0.8001)
					(clearance 0.1524)
				)
				(layer "B.Cu"
					(shape circle)
					(size 1.0033 1.0033)
					(clearance 0.10795)
				)
			)
		)
	)
	(footprint ""
		(layer "F.Cu")
		(at 381.587756 -298.020232)
		(property "Reference" "C3543"
			(at 0 0 0)
			(layer "F.SilkS")
			(hide yes)
			(effects
				(font
					(size 1.27 1.27)
				)
			)
		)
		(property "Value" ""
			(at 0 0 0)
			(layer "F.Fab")
			(effects
				(font
					(size 1.27 1.27)
				)
			)
		)
		(duplicate_pad_numbers_are_jumpers no)
		(fp_line
			(start -1.2954 -0.5842)
			(end 1.2954 -0.5842)
			(stroke
				(width 0.1524)
				(type default)
			)
			(layer "F.SilkS")
		)
		(fp_line
			(start -1.2954 0.5842)
			(end -1.2954 -0.5842)
			(stroke
				(width 0.1524)
				(type default)
			)
			(layer "F.SilkS")
		)
		(fp_line
			(start 1.2954 -0.5842)
			(end 1.2954 0.5842)
			(stroke
				(width 0.1524)
				(type default)
			)
			(layer "F.SilkS")
		)
		(fp_line
			(start 1.2954 0.5842)
			(end -1.2954 0.5842)
			(stroke
				(width 0.1524)
				(type default)
			)
			(layer "F.SilkS")
		)
		(fp_line
			(start -1.1938 -0.4064)
			(end -0.8636 -0.4064)
			(stroke
				(width 0.1)
				(type default)
			)
			(layer "F.Fab")
		)
		(fp_line
			(start -1.1938 0.4064)
			(end -1.1938 -0.4064)
			(stroke
				(width 0.1)
				(type default)
			)
			(layer "F.Fab")
		)
		(fp_line
			(start -0.8636 -0.4572)
			(end 0.8636 -0.4572)
			(stroke
				(width 0.1)
				(type default)
			)
			(layer "F.Fab")
		)
		(fp_line
			(start -0.8636 -0.4064)
			(end -0.8636 -0.4572)
			(stroke
				(width 0.1)
				(type default)
			)
			(layer "F.Fab")
		)
		(fp_line
			(start -0.8636 0.4064)
			(end -1.1938 0.4064)
			(stroke
				(width 0.1)
				(type default)
			)
			(layer "F.Fab")
		)
		(fp_line
			(start -0.8636 0.4572)
			(end -0.8636 0.4064)
			(stroke
				(width 0.1)
				(type default)
			)
			(layer "F.Fab")
		)
		(fp_line
			(start 0.8636 -0.4572)
			(end 0.8636 -0.4064)
			(stroke
				(width 0.1)
				(type default)
			)
			(layer "F.Fab")
		)
		(fp_line
			(start 0.8636 -0.4064)
			(end 1.1938 -0.4064)
			(stroke
				(width 0.1)
				(type default)
			)
			(layer "F.Fab")
		)
		(fp_line
			(start 0.8636 0.4064)
			(end 0.8636 0.4572)
			(stroke
				(width 0.1)
				(type default)
			)
			(layer "F.Fab")
		)
		(fp_line
			(start 0.8636 0.4572)
			(end -0.8636 0.4572)
			(stroke
				(width 0.1)
				(type default)
			)
			(layer "F.Fab")
		)
		(fp_line
			(start 1.1938 -0.4064)
			(end 1.1938 0.4064)
			(stroke
				(width 0.1)
				(type default)
			)
			(layer "F.Fab")
		)
		(fp_line
			(start 1.1938 0.4064)
			(end 0.8636 0.4064)
			(stroke
				(width 0.1)
				(type default)
			)
			(layer "F.Fab")
		)
		(pad "1" smd rect
			(at -0.7366 0 270)
			(size 0.7112 0.8128)
			(layers "F.Cu" "F.Mask" "F.Paste")
			(net "PCEPLL0_VDDA18_PEX3")
		)
		(pad "2" smd rect
			(at 0.7366 0 270)
			(size 0.7112 0.8128)
			(layers "F.Cu" "F.Mask" "F.Paste")
			(net "GND")
		)
	)
	(footprint ""
		(layer "F.Cu")
		(at 321.91325 -104.267508 -90)
		(property "Reference" "R745"
			(at 0 0 270)
			(layer "F.SilkS")
			(hide yes)
			(effects
				(font
					(size 1.27 1.27)
				)
			)
		)
		(property "Value" ""
			(at 0 0 270)
			(layer "F.Fab")
			(effects
				(font
					(size 1.27 1.27)
				)
			)
		)
		(duplicate_pad_numbers_are_jumpers no)
		(fp_line
			(start -0.7874 0.4064)
			(end -0.7874 -0.4064)
			(stroke
				(width 0.1524)
				(type default)
			)
			(layer "F.SilkS")
		)
		(fp_line
			(start 0.7874 0.4064)
			(end -0.7874 0.4064)
			(stroke
				(width 0.1524)
				(type default)
			)
			(layer "F.SilkS")
		)
		(fp_line
			(start -0.7874 -0.4064)
			(end 0.7874 -0.4064)
			(stroke
				(width 0.1524)
				(type default)
			)
			(layer "F.SilkS")
		)
		(fp_line
			(start 0.7874 -0.4064)
			(end 0.7874 0.4064)
			(stroke
				(width 0.1524)
				(type default)
			)
			(layer "F.SilkS")
		)
		(fp_line
			(start -0.67945 0.3048)
			(end -0.67945 -0.305054)
			(stroke
				(width 0.1)
				(type default)
			)
			(layer "F.Fab")
		)
		(fp_line
			(start -0.12065 0.3048)
			(end -0.67945 0.3048)
			(stroke
				(width 0.1)
				(type default)
			)
			(layer "F.Fab")
		)
		(fp_line
			(start 0.120396 0.3048)
			(end 0.120396 0.2794)
			(stroke
				(width 0.1)
				(type default)
			)
			(layer "F.Fab")
		)
		(fp_line
			(start 0.67945 0.3048)
			(end 0.120396 0.3048)
			(stroke
				(width 0.1)
				(type default)
			)
			(layer "F.Fab")
		)
		(fp_line
			(start -0.12065 0.2794)
			(end -0.12065 0.3048)
			(stroke
				(width 0.1)
				(type default)
			)
			(layer "F.Fab")
		)
		(fp_line
			(start 0.120396 0.2794)
			(end -0.12065 0.2794)
			(stroke
				(width 0.1)
				(type default)
			)
			(layer "F.Fab")
		)
		(fp_line
			(start -0.12065 -0.2794)
			(end 0.12065 -0.2794)
			(stroke
				(width 0.1)
				(type default)
			)
			(layer "F.Fab")
		)
		(fp_line
			(start 0.12065 -0.2794)
			(end 0.12065 -0.3048)
			(stroke
				(width 0.1)
				(type default)
			)
			(layer "F.Fab")
		)
		(fp_line
			(start 0.12065 -0.3048)
			(end 0.67945 -0.3048)
			(stroke
				(width 0.1)
				(type default)
			)
			(layer "F.Fab")
		)
		(fp_line
			(start 0.67945 -0.3048)
			(end 0.67945 0.3048)
			(stroke
				(width 0.1)
				(type default)
			)
			(layer "F.Fab")
		)
		(fp_line
			(start -0.67945 -0.305054)
			(end -0.12065 -0.305054)
			(stroke
				(width 0.1)
				(type default)
			)
			(layer "F.Fab")
		)
		(fp_line
			(start -0.12065 -0.305054)
			(end -0.12065 -0.2794)
			(stroke
				(width 0.1)
				(type default)
			)
			(layer "F.Fab")
		)
		(pad "1" smd circle
			(at -0.40005 0 270)
			(size 0 0)
			(layers "F.Cu" "F.Mask" "F.Paste")
			(net "P12V_NIC5")
		)
		(pad "2" smd circle
			(at 0.40005 0 270)
			(size 0 0)
			(layers "F.Cu" "F.Mask" "F.Paste")
			(net "P12V_NIC5_VIN_N")
		)
	)
	(footprint ""
		(layer "F.Cu")
		(at 21.541232 -25.915112 -90)
		(property "Reference" "R6198"
			(at 0 0 270)
			(layer "F.SilkS")
			(hide yes)
			(effects
				(font
					(size 1.27 1.27)
				)
			)
		)
		(property "Value" ""
			(at 0 0 270)
			(layer "F.Fab")
			(effects
				(font
					(size 1.27 1.27)
				)
			)
		)
		(duplicate_pad_numbers_are_jumpers no)
		(fp_line
			(start -0.7874 0.4064)
			(end -0.7874 -0.4064)
			(stroke
				(width 0.1524)
				(type default)
			)
			(layer "F.SilkS")
		)
		(fp_line
			(start 0.7874 0.4064)
			(end -0.7874 0.4064)
			(stroke
				(width 0.1524)
				(type default)
			)
			(layer "F.SilkS")
		)
		(fp_line
			(start -0.7874 -0.4064)
			(end 0.7874 -0.4064)
			(stroke
				(width 0.1524)
				(type default)
			)
			(layer "F.SilkS")
		)
		(fp_line
			(start 0.7874 -0.4064)
			(end 0.7874 0.4064)
			(stroke
				(width 0.1524)
				(type default)
			)
			(layer "F.SilkS")
		)
		(fp_line
			(start -0.67945 0.3048)
			(end -0.67945 -0.305054)
			(stroke
				(width 0.1)
				(type default)
			)
			(layer "F.Fab")
		)
		(fp_line
			(start -0.12065 0.3048)
			(end -0.67945 0.3048)
			(stroke
				(width 0.1)
				(type default)
			)
			(layer "F.Fab")
		)
		(fp_line
			(start 0.120396 0.3048)
			(end 0.120396 0.2794)
			(stroke
				(width 0.1)
				(type default)
			)
			(layer "F.Fab")
		)
		(fp_line
			(start 0.67945 0.3048)
			(end 0.120396 0.3048)
			(stroke
				(width 0.1)
				(type default)
			)
			(layer "F.Fab")
		)
		(fp_line
			(start -0.12065 0.2794)
			(end -0.12065 0.3048)
			(stroke
				(width 0.1)
				(type default)
			)
			(layer "F.Fab")
		)
		(fp_line
			(start 0.120396 0.2794)
			(end -0.12065 0.2794)
			(stroke
				(width 0.1)
				(type default)
			)
			(layer "F.Fab")
		)
		(fp_line
			(start -0.12065 -0.2794)
			(end 0.12065 -0.2794)
			(stroke
				(width 0.1)
				(type default)
			)
			(layer "F.Fab")
		)
		(fp_line
			(start 0.12065 -0.2794)
			(end 0.12065 -0.3048)
			(stroke
				(width 0.1)
				(type default)
			)
			(layer "F.Fab")
		)
		(fp_line
			(start 0.12065 -0.3048)
			(end 0.67945 -0.3048)
			(stroke
				(width 0.1)
				(type default)
			)
			(layer "F.Fab")
		)
		(fp_line
			(start 0.67945 -0.3048)
			(end 0.67945 0.3048)
			(stroke
				(width 0.1)
				(type default)
			)
			(layer "F.Fab")
		)
		(fp_line
			(start -0.67945 -0.305054)
			(end -0.12065 -0.305054)
			(stroke
				(width 0.1)
				(type default)
			)
			(layer "F.Fab")
		)
		(fp_line
			(start -0.12065 -0.305054)
			(end -0.12065 -0.2794)
			(stroke
				(width 0.1)
				(type default)
			)
			(layer "F.Fab")
		)
		(pad "1" smd circle
			(at -0.40005 0 270)
			(size 0 0)
			(layers "F.Cu" "F.Mask" "F.Paste")
			(net "GND")
		)
		(pad "2" smd circle
			(at 0.40005 0 270)
			(size 0 0)
			(layers "F.Cu" "F.Mask" "F.Paste")
			(net "SSD0_PWRDIS_R")
		)
	)
	(footprint ""
		(layer "F.Cu")
		(at 302.039782 -70.52437 90)
		(property "Reference" "PC429"
			(at 0 0 90)
			(layer "F.SilkS")
			(hide yes)
			(effects
				(font
					(size 1.27 1.27)
				)
			)
		)
		(property "Value" ""
			(at 0 0 90)
			(layer "F.Fab")
			(effects
				(font
					(size 1.27 1.27)
				)
			)
		)
		(duplicate_pad_numbers_are_jumpers no)
		(fp_line
			(start 1.524 -0.762)
			(end 1.524 0.762)
			(stroke
				(width 0.1524)
				(type default)
			)
			(layer "F.SilkS")
		)
		(fp_line
			(start -1.524 -0.762)
			(end 1.524 -0.762)
			(stroke
				(width 0.1524)
				(type default)
			)
			(layer "F.SilkS")
		)
		(fp_line
			(start 1.524 0.762)
			(end -1.524 0.762)
			(stroke
				(width 0.1524)
				(type default)
			)
			(layer "F.SilkS")
		)
		(fp_line
			(start -1.524 0.762)
			(end -1.524 -0.762)
			(stroke
				(width 0.1524)
				(type default)
			)
			(layer "F.SilkS")
		)
		(fp_line
			(start 1.1049 -0.724916)
			(end -1.1049 -0.724916)
			(stroke
				(width 0.1)
				(type default)
			)
			(layer "F.Fab")
		)
		(fp_line
			(start -1.1049 -0.724916)
			(end -1.1049 0.724916)
			(stroke
				(width 0.1)
				(type default)
			)
			(layer "F.Fab")
		)
		(fp_line
			(start 1.1049 0.724916)
			(end 1.1049 -0.724916)
			(stroke
				(width 0.1)
				(type default)
			)
			(layer "F.Fab")
		)
		(fp_line
			(start -1.1049 0.724916)
			(end 1.1049 0.724916)
			(stroke
				(width 0.1)
				(type default)
			)
			(layer "F.Fab")
		)
		(pad "1" smd rect
			(at -0.889 0 270)
			(size 1.016 1.27)
			(layers "F.Cu" "F.Mask" "F.Paste")
			(net "P12V_SSD10_R")
		)
		(pad "2" smd rect
			(at 0.889 0 270)
			(size 1.016 1.27)
			(layers "F.Cu" "F.Mask" "F.Paste")
			(net "GND")
		)
	)
	(footprint ""
		(layer "F.Cu")
		(at 190.245238 -412.21914 -90)
		(property "Reference" "R6776"
			(at 0 0 270)
			(layer "F.SilkS")
			(hide yes)
			(effects
				(font
					(size 1.27 1.27)
				)
			)
		)
		(property "Value" ""
			(at 0 0 270)
			(layer "F.Fab")
			(effects
				(font
					(size 1.27 1.27)
				)
			)
		)
		(duplicate_pad_numbers_are_jumpers no)
		(fp_line
			(start -0.7874 0.4064)
			(end -0.7874 -0.4064)
			(stroke
				(width 0.1524)
				(type default)
			)
			(layer "F.SilkS")
		)
		(fp_line
			(start 0.7874 0.4064)
			(end -0.7874 0.4064)
			(stroke
				(width 0.1524)
				(type default)
			)
			(layer "F.SilkS")
		)
		(fp_line
			(start -0.7874 -0.4064)
			(end 0.7874 -0.4064)
			(stroke
				(width 0.1524)
				(type default)
			)
			(layer "F.SilkS")
		)
		(fp_line
			(start 0.7874 -0.4064)
			(end 0.7874 0.4064)
			(stroke
				(width 0.1524)
				(type default)
			)
			(layer "F.SilkS")
		)
		(fp_line
			(start -0.67945 0.3048)
			(end -0.67945 -0.305054)
			(stroke
				(width 0.1)
				(type default)
			)
			(layer "F.Fab")
		)
		(fp_line
			(start -0.12065 0.3048)
			(end -0.67945 0.3048)
			(stroke
				(width 0.1)
				(type default)
			)
			(layer "F.Fab")
		)
		(fp_line
			(start 0.120396 0.3048)
			(end 0.120396 0.2794)
			(stroke
				(width 0.1)
				(type default)
			)
			(layer "F.Fab")
		)
		(fp_line
			(start 0.67945 0.3048)
			(end 0.120396 0.3048)
			(stroke
				(width 0.1)
				(type default)
			)
			(layer "F.Fab")
		)
		(fp_line
			(start -0.12065 0.2794)
			(end -0.12065 0.3048)
			(stroke
				(width 0.1)
				(type default)
			)
			(layer "F.Fab")
		)
		(fp_line
			(start 0.120396 0.2794)
			(end -0.12065 0.2794)
			(stroke
				(width 0.1)
				(type default)
			)
			(layer "F.Fab")
		)
		(fp_line
			(start -0.12065 -0.2794)
			(end 0.12065 -0.2794)
			(stroke
				(width 0.1)
				(type default)
			)
			(layer "F.Fab")
		)
		(fp_line
			(start 0.12065 -0.2794)
			(end 0.12065 -0.3048)
			(stroke
				(width 0.1)
				(type default)
			)
			(layer "F.Fab")
		)
		(fp_line
			(start 0.12065 -0.3048)
			(end 0.67945 -0.3048)
			(stroke
				(width 0.1)
				(type default)
			)
			(layer "F.Fab")
		)
		(fp_line
			(start 0.67945 -0.3048)
			(end 0.67945 0.3048)
			(stroke
				(width 0.1)
				(type default)
			)
			(layer "F.Fab")
		)
		(fp_line
			(start -0.67945 -0.305054)
			(end -0.12065 -0.305054)
			(stroke
				(width 0.1)
				(type default)
			)
			(layer "F.Fab")
		)
		(fp_line
			(start -0.12065 -0.305054)
			(end -0.12065 -0.2794)
			(stroke
				(width 0.1)
				(type default)
			)
			(layer "F.Fab")
		)
		(pad "1" smd circle
			(at -0.40005 0 270)
			(size 0 0)
			(layers "F.Cu" "F.Mask" "F.Paste")
			(net "P12V_AUX_FP_TRIGGER")
		)
		(pad "2" smd circle
			(at 0.40005 0 270)
			(size 0 0)
			(layers "F.Cu" "F.Mask" "F.Paste")
			(net "HSC_UV_R2_N")
		)
	)
)
